M48
;Layer_Color=9474304
;FILE_FORMAT=4:4
METRIC,LZ
;TYPE=PLATED
T1F00S00C0.3000
T2F00S00C0.3300
T3F00S00C0.3302
%
T01
X00046109Y00191339
X00044897Y00201849
X00051602Y00210033
X00062147Y00210899
X00070105Y00203927
X00080684Y00203805
X00084414Y00192195
X00073834
X00064966Y00186424
X00054498Y00184892
X00094994Y00192195
X00091264Y00203805
X00101844
X0011241Y00204354
X00122976Y00203805
X00133555
X00144033Y00205276
X00147587Y001943
X00137212Y00192229
X00126632Y00192195
X00116052
X00156682Y00199706
X00164283Y00207065
X00171765Y00214546
X00179246Y00222027
X00186727Y00229508
X00167427Y00226629
X00159946Y00219147
X00152465Y00211666
X00174908Y0023411
X0018239Y00241591
X0019016Y00248771
X00199634Y00253481
X00210131Y00254805
X00220711
X00231291
X00241871
X00252362Y00255974
X00255209Y00245785
X00234995Y00243195
X00224415
X00213835
X00203283Y00242429
X00194208Y00236989
T02
X00561Y00103
Y00123
X0056Y00143
X00536Y00208
X00523Y00208039
X00536Y00232691
X00522965Y00242
T03
X0002324Y000524
X0004864
X0007404
Y000778
Y001032
Y001286
Y00154
Y001794
Y002302
X0004864Y00154
Y001286
Y001032
Y000778
X0002324
Y001032
Y001286
Y00154
X0007404Y00027
X0009944
X0012484
X0015024
X0017564
X0020104
X0022644
X0025184Y000524
X0027724
X0030264
X0032804
X0035344
X0037884
X0040424
X0042964
X0045504
X0048044
Y001032
Y001286
X0045504
X0042964
X0040424
X00404029Y00103411
X0042964Y001032
Y000778
X0040424
X0042964Y00154
X0045504
X0048044
Y001794
Y002048
X0045504Y001794
X0042964Y002302
X0040424
Y002048
X0037884Y001794
X0035344
Y00154
X0032804
Y001794
X0030264
Y00154
Y001286
X0032804
X0027724
Y00154
Y001794
X0025184
Y00154
Y001286
X0022644
Y00154
Y001794
Y002048
Y002302
X0020104
Y002048
Y001794
Y00154
Y001286
X0017564
Y00154
Y001794
Y002048
X0015024Y002302
X0012484
Y00154
X0015024
Y001794
Y001032
Y000778
X0017564
Y000524
X0020104
Y001032
X0022644
X0027724Y000778
X0015024Y000524
X0012484
Y000778
X0009944
Y000524
Y00154
X0030264Y002302
X0050584Y002048
Y001794
Y00154
Y001286
X0055664Y00154
X0058204
X0063284
Y002048
Y002302
X0060744
Y001794
X0055664
Y002048
Y000524
X0058204
X0060744
X0063284
X0060744Y00027
X0053124Y000524
X0050584
X0053124Y002556
X0055664
X0058204
X0060744
X0063284
X0060744Y00281
X0058204
X0055664
X0053124
X0050584
X0048044
Y002556
X0045504
Y00281
X0042964
Y002556
X0040424
Y00281
X0037884
X0035344
Y002556
X0032804Y00281
X0030264
X0027724
X0025184
X0022644
X0020104
X0017564
Y002556
X0015024
Y00281
X0012484
Y002556
X0009944
Y00281
X0007404
Y002556
X0004864
X0002324
M30
